(kicad_pcb
	(version 20260206)
	(generator "pcbnew")
	(generator_version "10.0")
	(general
		(thickness 1.6)
		(legacy_teardrops no)
	)
	(paper "A4")
	(title_block
		(title "baseboard — 13948-1b.1110WZS1818.brd")
		(comment 1 "Honey Badger (Wiwynn) / footprints 2277-2283 of 2523")
	)
	(layers
		(0 "F.Cu" signal "TOP")
		(4 "In1.Cu" signal "L2GND")
		(6 "In2.Cu" signal "L3")
		(8 "In3.Cu" signal "L4VCC")
		(10 "In4.Cu" signal "L5VCC")
		(12 "In5.Cu" signal "L6")
		(14 "In6.Cu" signal "L7GND")
		(2 "B.Cu" signal "BOTTOM")
		(9 "F.Adhes" user "F.Adhesive")
		(11 "B.Adhes" user "B.Adhesive")
		(13 "F.Paste" user "Package Geometry/Pastemask Top")
		(15 "B.Paste" user "Package Geometry/Pastemask Bottom")
		(5 "F.SilkS" user "Ref Des/Silkscreen Top")
		(7 "B.SilkS" user "Ref Des/Silkscreen Bottom")
		(1 "F.Mask" user "Board Geometry/Soldermask Top")
		(3 "B.Mask" user "Board Geometry/Soldermask Bottom")
		(17 "Dwgs.User" user "User.Drawings")
		(19 "Cmts.User" user "User.Comments")
		(21 "Eco1.User" user "User.Eco1")
		(23 "Eco2.User" user "User.Eco2")
		(25 "Edge.Cuts" user "Board Geometry/Outline")
		(27 "Margin" user)
		(31 "F.CrtYd" user "Package Geometry/Place Bound Top")
		(29 "B.CrtYd" user "Package Geometry/Place Bound Bottom")
		(35 "F.Fab" user "Ref Des/Assembly Top")
		(33 "B.Fab" user "Ref Des/Assembly Bottom")
	)
	(footprint ""
		(layer "B.Cu")
		(at 297.2308 -172.5422 90)
		(property "Reference" "R335"
			(at 0 0 90)
			(layer "B.SilkS")
			(hide yes)
			(effects
				(font
					(size 1.27 1.27)
				)
				(justify mirror)
			)
		)
		(property "Value" "10KR2F-2-GP"
			(at -0.064008 -3.993896 90)
			(unlocked yes)
			(layer "B.Fab")
			(hide yes)
			(effects
				(font
					(size 1.016 1.016)
					(thickness 0.1524)
				)
				(justify mirror)
			)
		)
		(property "Device Type" "R402H16"
			(at -0.064008 -5.517896 90)
			(unlocked yes)
			(layer "B.Fab")
			(hide yes)
			(effects
				(font
					(size 1.016 1.016)
					(thickness 0.1524)
				)
				(justify mirror)
			)
		)
		(duplicate_pad_numbers_are_jumpers no)
		(fp_line
			(start 0.508 -0.9398)
			(end 0.508 0.9398)
			(stroke
				(width 0.1524)
				(type default)
			)
			(layer "B.SilkS")
		)
		(fp_line
			(start -0.508 -0.9398)
			(end 0.508 -0.9398)
			(stroke
				(width 0.1524)
				(type default)
			)
			(layer "B.SilkS")
		)
		(fp_rect
			(start 0.508 0.9398)
			(end -0.508 -0.9398)
			(stroke
				(width 0)
				(type default)
			)
			(fill no)
			(layer "B.CrtYd")
		)
		(fp_rect
			(start 0.508 0.9398)
			(end -0.508 -0.9398)
			(stroke
				(width 0)
				(type default)
			)
			(fill no)
			(layer "B.Fab")
		)
		(pad "1" smd custom
			(at 0 -0.4445 270)
			(size 0.1397 0.1397)
			(layers "B.Cu" "B.Mask" "B.Paste")
			(net "GND")
			(options
				(clearance outline)
				(anchor circle)
			)
			(primitives
				(gr_poly
					(pts
						(arc
							(start -0.1778 0.2794)
							(mid -0.249642 0.249642)
							(end -0.2794 0.1778)
						)
						(arc
							(start -0.2794 -0.1778)
							(mid -0.249642 -0.249642)
							(end -0.1778 -0.2794)
						)
						(arc
							(start 0.1778 -0.2794)
							(mid 0.249642 -0.249642)
							(end 0.2794 -0.1778)
						)
						(arc
							(start 0.2794 0.1778)
							(mid 0.249642 0.249642)
							(end 0.1778 0.2794)
						)
					)
					(width 0)
					(fill yes)
				)
			)
		)
		(pad "2" smd custom
			(at 0 0.4445 270)
			(size 0.1397 0.1397)
			(layers "B.Cu" "B.Mask" "B.Paste")
			(net "BMC0_JTAG_RTCK")
			(options
				(clearance outline)
				(anchor circle)
			)
			(primitives
				(gr_poly
					(pts
						(arc
							(start -0.1778 0.2794)
							(mid -0.249642 0.249642)
							(end -0.2794 0.1778)
						)
						(arc
							(start -0.2794 -0.1778)
							(mid -0.249642 -0.249642)
							(end -0.1778 -0.2794)
						)
						(arc
							(start 0.1778 -0.2794)
							(mid 0.249642 -0.249642)
							(end 0.2794 -0.1778)
						)
						(arc
							(start 0.2794 0.1778)
							(mid 0.249642 0.249642)
							(end 0.1778 0.2794)
						)
					)
					(width 0)
					(fill yes)
				)
			)
		)
	)
	(footprint ""
		(layer "B.Cu")
		(at 94.87916 -31.623)
		(property "Reference" "SC863"
			(at 0 0 0)
			(layer "B.SilkS")
			(hide yes)
			(effects
				(font
					(size 1.27 1.27)
				)
				(justify mirror)
			)
		)
		(property "Value" "SCD22U6D3V1MX-1-GP"
			(at 2.8321 -1.7399 0)
			(unlocked yes)
			(layer "B.Fab")
			(hide yes)
			(effects
				(font
					(size 1.016 1.016)
					(thickness 0.1524)
				)
				(justify mirror)
			)
		)
		(property "Device Type" "C0201H13"
			(at 2.8321 -3.2639 0)
			(unlocked yes)
			(layer "B.Fab")
			(hide yes)
			(effects
				(font
					(size 1.016 1.016)
					(thickness 0.1524)
				)
				(justify mirror)
			)
		)
		(duplicate_pad_numbers_are_jumpers no)
		(fp_rect
			(start 0.2794 0.6477)
			(end -0.2794 -0.6477)
			(stroke
				(width 0)
				(type default)
			)
			(fill no)
			(layer "B.CrtYd")
		)
		(fp_rect
			(start 0.2794 0.6477)
			(end -0.2794 -0.6477)
			(stroke
				(width 0)
				(type default)
			)
			(fill no)
			(layer "B.Fab")
		)
		(pad "1" smd custom
			(at 0 -0.2794 180)
			(size 0.0762 0.0762)
			(layers "B.Cu" "B.Mask" "B.Paste")
			(net "PCIE_SAS_C_CPU_RX_P1")
			(options
				(clearance outline)
				(anchor circle)
			)
			(primitives
				(gr_poly
					(pts
						(arc
							(start 0.1524 0.127)
							(mid 0.137521 0.162921)
							(end 0.1016 0.1778)
						)
						(arc
							(start -0.1016 0.1778)
							(mid -0.137521 0.162921)
							(end -0.1524 0.127)
						)
						(arc
							(start -0.1524 -0.127)
							(mid -0.137521 -0.162921)
							(end -0.1016 -0.1778)
						)
						(arc
							(start 0.1016 -0.1778)
							(mid 0.137521 -0.162921)
							(end 0.1524 -0.127)
						)
					)
					(width 0)
					(fill yes)
				)
			)
		)
		(pad "2" smd custom
			(at 0 0.2794 180)
			(size 0.0762 0.0762)
			(layers "B.Cu" "B.Mask" "B.Paste")
			(net "PCIE_SAS_CPU_RX_P1")
			(options
				(clearance outline)
				(anchor circle)
			)
			(primitives
				(gr_poly
					(pts
						(arc
							(start 0.1524 0.127)
							(mid 0.137521 0.162921)
							(end 0.1016 0.1778)
						)
						(arc
							(start -0.1016 0.1778)
							(mid -0.137521 0.162921)
							(end -0.1524 0.127)
						)
						(arc
							(start -0.1524 -0.127)
							(mid -0.137521 -0.162921)
							(end -0.1016 -0.1778)
						)
						(arc
							(start 0.1016 -0.1778)
							(mid 0.137521 -0.162921)
							(end 0.1524 -0.127)
						)
					)
					(width 0)
					(fill yes)
				)
			)
		)
	)
	(footprint ""
		(layer "B.Cu")
		(at 299.339 -164.084)
		(property "Reference" "R538"
			(at 0 0 0)
			(layer "B.SilkS")
			(hide yes)
			(effects
				(font
					(size 1.27 1.27)
				)
				(justify mirror)
			)
		)
		(property "Value" "0R2J-2-GP"
			(at -0.064008 -3.993896 0)
			(unlocked yes)
			(layer "B.Fab")
			(hide yes)
			(effects
				(font
					(size 1.016 1.016)
					(thickness 0.1524)
				)
				(justify mirror)
			)
		)
		(property "Device Type" "R402H16"
			(at -0.064008 -5.517896 0)
			(unlocked yes)
			(layer "B.Fab")
			(hide yes)
			(effects
				(font
					(size 1.016 1.016)
					(thickness 0.1524)
				)
				(justify mirror)
			)
		)
		(duplicate_pad_numbers_are_jumpers no)
		(fp_line
			(start -0.508 -0.9398)
			(end 0.508 -0.9398)
			(stroke
				(width 0.1524)
				(type default)
			)
			(layer "B.SilkS")
		)
		(fp_line
			(start 0.508 -0.9398)
			(end 0.508 0.9398)
			(stroke
				(width 0.1524)
				(type default)
			)
			(layer "B.SilkS")
		)
		(fp_rect
			(start 0.508 0.9398)
			(end -0.508 -0.9398)
			(stroke
				(width 0)
				(type default)
			)
			(fill no)
			(layer "B.CrtYd")
		)
		(fp_rect
			(start 0.508 0.9398)
			(end -0.508 -0.9398)
			(stroke
				(width 0)
				(type default)
			)
			(fill no)
			(layer "B.Fab")
		)
		(pad "1" smd custom
			(at 0 -0.4445 180)
			(size 0.1397 0.1397)
			(layers "B.Cu" "B.Mask" "B.Paste")
			(net "EXP_ID_BMC")
			(options
				(clearance outline)
				(anchor circle)
			)
			(primitives
				(gr_poly
					(pts
						(arc
							(start -0.1778 0.2794)
							(mid -0.249642 0.249642)
							(end -0.2794 0.1778)
						)
						(arc
							(start -0.2794 -0.1778)
							(mid -0.249642 -0.249642)
							(end -0.1778 -0.2794)
						)
						(arc
							(start 0.1778 -0.2794)
							(mid 0.249642 -0.249642)
							(end 0.2794 -0.1778)
						)
						(arc
							(start 0.2794 0.1778)
							(mid 0.249642 0.249642)
							(end 0.1778 0.2794)
						)
					)
					(width 0)
					(fill yes)
				)
			)
		)
		(pad "2" smd custom
			(at 0 0.4445 180)
			(size 0.1397 0.1397)
			(layers "B.Cu" "B.Mask" "B.Paste")
			(net "EXP_ID")
			(options
				(clearance outline)
				(anchor circle)
			)
			(primitives
				(gr_poly
					(pts
						(arc
							(start -0.1778 0.2794)
							(mid -0.249642 0.249642)
							(end -0.2794 0.1778)
						)
						(arc
							(start -0.2794 -0.1778)
							(mid -0.249642 -0.249642)
							(end -0.1778 -0.2794)
						)
						(arc
							(start 0.1778 -0.2794)
							(mid 0.249642 -0.249642)
							(end 0.2794 -0.1778)
						)
						(arc
							(start 0.2794 0.1778)
							(mid 0.249642 0.249642)
							(end 0.1778 0.2794)
						)
					)
					(width 0)
					(fill yes)
				)
			)
		)
	)
	(footprint ""
		(layer "B.Cu")
		(at 108.020612 -215.011 -90)
		(property "Reference" "SR900"
			(at 0 0 90)
			(layer "B.SilkS")
			(hide yes)
			(effects
				(font
					(size 1.27 1.27)
				)
				(justify mirror)
			)
		)
		(property "Value" "4K7R2F-GP"
			(at -0.064008 -3.993896 270)
			(unlocked yes)
			(layer "B.Fab")
			(hide yes)
			(effects
				(font
					(size 1.016 1.016)
					(thickness 0.1524)
				)
				(justify mirror)
			)
		)
		(property "Device Type" "R402H16"
			(at -0.064008 -5.517896 270)
			(unlocked yes)
			(layer "B.Fab")
			(hide yes)
			(effects
				(font
					(size 1.016 1.016)
					(thickness 0.1524)
				)
				(justify mirror)
			)
		)
		(duplicate_pad_numbers_are_jumpers no)
		(fp_line
			(start -0.508 -0.9398)
			(end 0.508 -0.9398)
			(stroke
				(width 0.1524)
				(type default)
			)
			(layer "B.SilkS")
		)
		(fp_line
			(start 0.508 -0.9398)
			(end 0.508 0.9398)
			(stroke
				(width 0.1524)
				(type default)
			)
			(layer "B.SilkS")
		)
		(fp_rect
			(start 0.508 0.9398)
			(end -0.508 -0.9398)
			(stroke
				(width 0)
				(type default)
			)
			(fill no)
			(layer "B.CrtYd")
		)
		(fp_rect
			(start 0.508 0.9398)
			(end -0.508 -0.9398)
			(stroke
				(width 0)
				(type default)
			)
			(fill no)
			(layer "B.Fab")
		)
		(pad "1" smd custom
			(at 0 -0.4445 90)
			(size 0.1397 0.1397)
			(layers "B.Cu" "B.Mask" "B.Paste")
			(net "REDV_I2C_A0")
			(options
				(clearance outline)
				(anchor circle)
			)
			(primitives
				(gr_poly
					(pts
						(arc
							(start -0.1778 0.2794)
							(mid -0.249642 0.249642)
							(end -0.2794 0.1778)
						)
						(arc
							(start -0.2794 -0.1778)
							(mid -0.249642 -0.249642)
							(end -0.1778 -0.2794)
						)
						(arc
							(start 0.1778 -0.2794)
							(mid 0.249642 -0.249642)
							(end 0.2794 -0.1778)
						)
						(arc
							(start 0.2794 0.1778)
							(mid 0.249642 0.249642)
							(end 0.1778 0.2794)
						)
					)
					(width 0)
					(fill yes)
				)
			)
		)
		(pad "2" smd custom
			(at 0 0.4445 90)
			(size 0.1397 0.1397)
			(layers "B.Cu" "B.Mask" "B.Paste")
			(net "GND")
			(options
				(clearance outline)
				(anchor circle)
			)
			(primitives
				(gr_poly
					(pts
						(arc
							(start -0.1778 0.2794)
							(mid -0.249642 0.249642)
							(end -0.2794 0.1778)
						)
						(arc
							(start -0.2794 -0.1778)
							(mid -0.249642 -0.249642)
							(end -0.1778 -0.2794)
						)
						(arc
							(start 0.1778 -0.2794)
							(mid 0.249642 -0.249642)
							(end 0.2794 -0.1778)
						)
						(arc
							(start 0.2794 0.1778)
							(mid 0.249642 0.249642)
							(end 0.1778 0.2794)
						)
					)
					(width 0)
					(fill yes)
				)
			)
		)
	)
	(footprint ""
		(layer "B.Cu")
		(at 112.30737 -92.1258 90)
		(property "Reference" "SC1253"
			(at 0 0 90)
			(layer "B.SilkS")
			(hide yes)
			(effects
				(font
					(size 1.27 1.27)
				)
				(justify mirror)
			)
		)
		(property "Value" "SCD1U6D3V1KX-GP"
			(at 2.8321 -1.7399 90)
			(unlocked yes)
			(layer "B.Fab")
			(hide yes)
			(effects
				(font
					(size 1.016 1.016)
					(thickness 0.1524)
				)
				(justify mirror)
			)
		)
		(property "Device Type" "C0201H13"
			(at 2.8321 -3.2639 90)
			(unlocked yes)
			(layer "B.Fab")
			(hide yes)
			(effects
				(font
					(size 1.016 1.016)
					(thickness 0.1524)
				)
				(justify mirror)
			)
		)
		(duplicate_pad_numbers_are_jumpers no)
		(fp_rect
			(start 0.2794 0.6477)
			(end -0.2794 -0.6477)
			(stroke
				(width 0)
				(type default)
			)
			(fill no)
			(layer "B.CrtYd")
		)
		(fp_rect
			(start 0.2794 0.6477)
			(end -0.2794 -0.6477)
			(stroke
				(width 0)
				(type default)
			)
			(fill no)
			(layer "B.Fab")
		)
		(pad "1" smd custom
			(at 0 -0.2794 270)
			(size 0.0762 0.0762)
			(layers "B.Cu" "B.Mask" "B.Paste")
			(net "P0V9_E")
			(options
				(clearance outline)
				(anchor circle)
			)
			(primitives
				(gr_poly
					(pts
						(arc
							(start 0.1524 0.127)
							(mid 0.137521 0.162921)
							(end 0.1016 0.1778)
						)
						(arc
							(start -0.1016 0.1778)
							(mid -0.137521 0.162921)
							(end -0.1524 0.127)
						)
						(arc
							(start -0.1524 -0.127)
							(mid -0.137521 -0.162921)
							(end -0.1016 -0.1778)
						)
						(arc
							(start 0.1016 -0.1778)
							(mid 0.137521 -0.162921)
							(end 0.1524 -0.127)
						)
					)
					(width 0)
					(fill yes)
				)
			)
		)
		(pad "2" smd custom
			(at 0 0.2794 270)
			(size 0.0762 0.0762)
			(layers "B.Cu" "B.Mask" "B.Paste")
			(net "GND")
			(options
				(clearance outline)
				(anchor circle)
			)
			(primitives
				(gr_poly
					(pts
						(arc
							(start 0.1524 0.127)
							(mid 0.137521 0.162921)
							(end 0.1016 0.1778)
						)
						(arc
							(start -0.1016 0.1778)
							(mid -0.137521 0.162921)
							(end -0.1524 0.127)
						)
						(arc
							(start -0.1524 -0.127)
							(mid -0.137521 -0.162921)
							(end -0.1016 -0.1778)
						)
						(arc
							(start 0.1016 -0.1778)
							(mid 0.137521 -0.162921)
							(end 0.1524 -0.127)
						)
					)
					(width 0)
					(fill yes)
				)
			)
		)
	)
	(footprint ""
		(layer "B.Cu")
		(at 274.193 -183.769 90)
		(property "Reference" "R350"
			(at 0 0 90)
			(layer "B.SilkS")
			(hide yes)
			(effects
				(font
					(size 1.27 1.27)
				)
				(justify mirror)
			)
		)
		(property "Value" "3K3R2F-2-GP"
			(at -0.064008 -3.993896 90)
			(unlocked yes)
			(layer "B.Fab")
			(hide yes)
			(effects
				(font
					(size 1.016 1.016)
					(thickness 0.1524)
				)
				(justify mirror)
			)
		)
		(property "Device Type" "R402H16"
			(at -0.064008 -5.517896 90)
			(unlocked yes)
			(layer "B.Fab")
			(hide yes)
			(effects
				(font
					(size 1.016 1.016)
					(thickness 0.1524)
				)
				(justify mirror)
			)
		)
		(duplicate_pad_numbers_are_jumpers no)
		(fp_line
			(start 0.508 -0.9398)
			(end 0.508 0.9398)
			(stroke
				(width 0.1524)
				(type default)
			)
			(layer "B.SilkS")
		)
		(fp_line
			(start -0.508 -0.9398)
			(end 0.508 -0.9398)
			(stroke
				(width 0.1524)
				(type default)
			)
			(layer "B.SilkS")
		)
		(fp_rect
			(start 0.508 0.9398)
			(end -0.508 -0.9398)
			(stroke
				(width 0)
				(type default)
			)
			(fill no)
			(layer "B.CrtYd")
		)
		(fp_rect
			(start 0.508 0.9398)
			(end -0.508 -0.9398)
			(stroke
				(width 0)
				(type default)
			)
			(fill no)
			(layer "B.Fab")
		)
		(pad "1" smd custom
			(at 0 -0.4445 270)
			(size 0.1397 0.1397)
			(layers "B.Cu" "B.Mask" "B.Paste")
			(net "P3V3_STBY")
			(options
				(clearance outline)
				(anchor circle)
			)
			(primitives
				(gr_poly
					(pts
						(arc
							(start -0.1778 0.2794)
							(mid -0.249642 0.249642)
							(end -0.2794 0.1778)
						)
						(arc
							(start -0.2794 -0.1778)
							(mid -0.249642 -0.249642)
							(end -0.1778 -0.2794)
						)
						(arc
							(start 0.1778 -0.2794)
							(mid 0.249642 -0.249642)
							(end 0.2794 -0.1778)
						)
						(arc
							(start 0.2794 0.1778)
							(mid 0.249642 0.249642)
							(end 0.1778 0.2794)
						)
					)
					(width 0)
					(fill yes)
				)
			)
		)
		(pad "2" smd custom
			(at 0 0.4445 270)
			(size 0.1397 0.1397)
			(layers "B.Cu" "B.Mask" "B.Paste")
			(net "ROMD2")
			(options
				(clearance outline)
				(anchor circle)
			)
			(primitives
				(gr_poly
					(pts
						(arc
							(start -0.1778 0.2794)
							(mid -0.249642 0.249642)
							(end -0.2794 0.1778)
						)
						(arc
							(start -0.2794 -0.1778)
							(mid -0.249642 -0.249642)
							(end -0.1778 -0.2794)
						)
						(arc
							(start 0.1778 -0.2794)
							(mid 0.249642 -0.249642)
							(end 0.2794 -0.1778)
						)
						(arc
							(start 0.2794 0.1778)
							(mid 0.249642 0.249642)
							(end 0.1778 0.2794)
						)
					)
					(width 0)
					(fill yes)
				)
			)
		)
	)
	(footprint ""
		(layer "B.Cu")
		(at 86.11616 -50.165 90)
		(property "Reference" "SR632"
			(at 0 0 90)
			(layer "B.SilkS")
			(hide yes)
			(effects
				(font
					(size 1.27 1.27)
				)
				(justify mirror)
			)
		)
		(property "Value" "2K2R2F-GP"
			(at -0.064008 -3.993896 90)
			(unlocked yes)
			(layer "B.Fab")
			(hide yes)
			(effects
				(font
					(size 1.016 1.016)
					(thickness 0.1524)
				)
				(justify mirror)
			)
		)
		(property "Device Type" "R402H16"
			(at -0.064008 -5.517896 90)
			(unlocked yes)
			(layer "B.Fab")
			(hide yes)
			(effects
				(font
					(size 1.016 1.016)
					(thickness 0.1524)
				)
				(justify mirror)
			)
		)
		(duplicate_pad_numbers_are_jumpers no)
		(fp_line
			(start 0.508 -0.9398)
			(end 0.508 0.9398)
			(stroke
				(width 0.1524)
				(type default)
			)
			(layer "B.SilkS")
		)
		(fp_line
			(start -0.508 -0.9398)
			(end 0.508 -0.9398)
			(stroke
				(width 0.1524)
				(type default)
			)
			(layer "B.SilkS")
		)
		(fp_rect
			(start 0.508 0.9398)
			(end -0.508 -0.9398)
			(stroke
				(width 0)
				(type default)
			)
			(fill no)
			(layer "B.CrtYd")
		)
		(fp_rect
			(start 0.508 0.9398)
			(end -0.508 -0.9398)
			(stroke
				(width 0)
				(type default)
			)
			(fill no)
			(layer "B.Fab")
		)
		(pad "1" smd custom
			(at 0 -0.4445 270)
			(size 0.1397 0.1397)
			(layers "B.Cu" "B.Mask" "B.Paste")
			(net "P1V8_C")
			(options
				(clearance outline)
				(anchor circle)
			)
			(primitives
				(gr_poly
					(pts
						(arc
							(start -0.1778 0.2794)
							(mid -0.249642 0.249642)
							(end -0.2794 0.1778)
						)
						(arc
							(start -0.2794 -0.1778)
							(mid -0.249642 -0.249642)
							(end -0.1778 -0.2794)
						)
						(arc
							(start 0.1778 -0.2794)
							(mid 0.249642 -0.249642)
							(end 0.2794 -0.1778)
						)
						(arc
							(start 0.2794 0.1778)
							(mid 0.249642 0.249642)
							(end 0.1778 0.2794)
						)
					)
					(width 0)
					(fill yes)
				)
			)
		)
		(pad "2" smd custom
			(at 0 0.4445 270)
			(size 0.1397 0.1397)
			(layers "B.Cu" "B.Mask" "B.Paste")
			(net "SIO_DOUT_1")
			(options
				(clearance outline)
				(anchor circle)
			)
			(primitives
				(gr_poly
					(pts
						(arc
							(start -0.1778 0.2794)
							(mid -0.249642 0.249642)
							(end -0.2794 0.1778)
						)
						(arc
							(start -0.2794 -0.1778)
							(mid -0.249642 -0.249642)
							(end -0.1778 -0.2794)
						)
						(arc
							(start 0.1778 -0.2794)
							(mid 0.249642 -0.249642)
							(end 0.2794 -0.1778)
						)
						(arc
							(start 0.2794 0.1778)
							(mid 0.249642 0.249642)
							(end 0.1778 0.2794)
						)
					)
					(width 0)
					(fill yes)
				)
			)
		)
	)
)
